(kicad_pcb
	(version 20260206)
	(generator "pcbnew")
	(generator_version "10.0")
	(general
		(thickness 1.6)
		(legacy_teardrops no)
	)
	(paper "A4")
	(title_block
		(title "04192023_DAF0TMB3IC0_F0TG_MB_C_brd_V02_OCP.brd")
		(comment 1 "Grand Teton / footprints 329-334 of 8354")
	)
	(layers
		(0 "F.Cu" signal "TOP")
		(4 "In1.Cu" signal "GND")
		(6 "In2.Cu" signal "IN1")
		(8 "In3.Cu" signal "GND1")
		(10 "In4.Cu" signal "IN2")
		(12 "In5.Cu" signal "GND2")
		(14 "In6.Cu" signal "IN3")
		(16 "In7.Cu" signal "GND3")
		(18 "In8.Cu" signal "VCC")
		(20 "In9.Cu" signal "VCC1")
		(22 "In10.Cu" signal "GND4")
		(24 "In11.Cu" signal "IN4")
		(26 "In12.Cu" signal "GND5")
		(28 "In13.Cu" signal "IN5")
		(30 "In14.Cu" signal "GND6")
		(32 "In15.Cu" signal "IN6")
		(34 "In16.Cu" signal "GND7")
		(2 "B.Cu" signal "BOTTOM")
		(9 "F.Adhes" user "F.Adhesive")
		(11 "B.Adhes" user "B.Adhesive")
		(13 "F.Paste" user "Package Geometry/Pastemask Top")
		(15 "B.Paste" user "Package Geometry/Pastemask Bottom")
		(5 "F.SilkS" user "Ref Des/Silkscreen Top")
		(7 "B.SilkS" user "Ref Des/Silkscreen Bottom")
		(1 "F.Mask" user "Board Geometry/Soldermask Top")
		(3 "B.Mask" user "Board Geometry/Soldermask Bottom")
		(17 "Dwgs.User" user "User.Drawings")
		(19 "Cmts.User" user "User.Comments")
		(21 "Eco1.User" user "User.Eco1")
		(23 "Eco2.User" user "User.Eco2")
		(25 "Edge.Cuts" user "Board Geometry/Outline")
		(27 "Margin" user)
		(31 "F.CrtYd" user "Package Geometry/Place Bound Top")
		(29 "B.CrtYd" user "Package Geometry/Place Bound Bottom")
		(35 "F.Fab" user "Ref Des/Assembly Top")
		(33 "B.Fab" user "Ref Des/Assembly Bottom")
	)
	(footprint ""
		(layer "F.Cu")
		(at 10.066782 -404.976584 180)
		(property "Reference" "PR6538"
			(at 0 0 180)
			(layer "F.SilkS")
			(hide yes)
			(effects
				(font
					(size 1.27 1.27)
				)
			)
		)
		(property "Value" ""
			(at 0 0 180)
			(layer "F.Fab")
			(effects
				(font
					(size 1.27 1.27)
				)
			)
		)
		(duplicate_pad_numbers_are_jumpers no)
		(fp_line
			(start 0.7874 0.4064)
			(end -0.7874 0.4064)
			(stroke
				(width 0.1524)
				(type default)
			)
			(layer "F.SilkS")
		)
		(fp_line
			(start 0.7874 -0.4064)
			(end 0.7874 0.4064)
			(stroke
				(width 0.1524)
				(type default)
			)
			(layer "F.SilkS")
		)
		(fp_line
			(start -0.7874 0.4064)
			(end -0.7874 -0.4064)
			(stroke
				(width 0.1524)
				(type default)
			)
			(layer "F.SilkS")
		)
		(fp_line
			(start -0.7874 -0.4064)
			(end 0.7874 -0.4064)
			(stroke
				(width 0.1524)
				(type default)
			)
			(layer "F.SilkS")
		)
		(fp_line
			(start 0.67945 0.3048)
			(end 0.120396 0.3048)
			(stroke
				(width 0.1)
				(type default)
			)
			(layer "F.Fab")
		)
		(fp_line
			(start 0.67945 -0.3048)
			(end 0.67945 0.3048)
			(stroke
				(width 0.1)
				(type default)
			)
			(layer "F.Fab")
		)
		(fp_line
			(start 0.12065 -0.2794)
			(end 0.12065 -0.3048)
			(stroke
				(width 0.1)
				(type default)
			)
			(layer "F.Fab")
		)
		(fp_line
			(start 0.12065 -0.3048)
			(end 0.67945 -0.3048)
			(stroke
				(width 0.1)
				(type default)
			)
			(layer "F.Fab")
		)
		(fp_line
			(start 0.120396 0.3048)
			(end 0.120396 0.2794)
			(stroke
				(width 0.1)
				(type default)
			)
			(layer "F.Fab")
		)
		(fp_line
			(start 0.120396 0.2794)
			(end -0.12065 0.2794)
			(stroke
				(width 0.1)
				(type default)
			)
			(layer "F.Fab")
		)
		(fp_line
			(start -0.12065 0.3048)
			(end -0.67945 0.3048)
			(stroke
				(width 0.1)
				(type default)
			)
			(layer "F.Fab")
		)
		(fp_line
			(start -0.12065 0.2794)
			(end -0.12065 0.3048)
			(stroke
				(width 0.1)
				(type default)
			)
			(layer "F.Fab")
		)
		(fp_line
			(start -0.12065 -0.2794)
			(end 0.12065 -0.2794)
			(stroke
				(width 0.1)
				(type default)
			)
			(layer "F.Fab")
		)
		(fp_line
			(start -0.12065 -0.305054)
			(end -0.12065 -0.2794)
			(stroke
				(width 0.1)
				(type default)
			)
			(layer "F.Fab")
		)
		(fp_line
			(start -0.67945 0.3048)
			(end -0.67945 -0.305054)
			(stroke
				(width 0.1)
				(type default)
			)
			(layer "F.Fab")
		)
		(fp_line
			(start -0.67945 -0.305054)
			(end -0.12065 -0.305054)
			(stroke
				(width 0.1)
				(type default)
			)
			(layer "F.Fab")
		)
		(pad "1" smd circle
			(at -0.40005 0 180)
			(size 0 0)
			(layers "F.Cu" "F.Mask" "F.Paste")
			(net "P0V9_RETIMER_CPU1_VCC")
		)
		(pad "2" smd circle
			(at 0.40005 0 180)
			(size 0 0)
			(layers "F.Cu" "F.Mask" "F.Paste")
			(net "P3V3_AUX")
		)
	)
	(footprint ""
		(layer "F.Cu")
		(at 219.47251 -131.454144 90)
		(property "Reference" "R1650"
			(at 0 0 90)
			(layer "F.SilkS")
			(hide yes)
			(effects
				(font
					(size 1.27 1.27)
				)
			)
		)
		(property "Value" ""
			(at 0 0 90)
			(layer "F.Fab")
			(effects
				(font
					(size 1.27 1.27)
				)
			)
		)
		(duplicate_pad_numbers_are_jumpers no)
		(fp_line
			(start 0.7874 -0.4064)
			(end 0.7874 0.4064)
			(stroke
				(width 0.1524)
				(type default)
			)
			(layer "F.SilkS")
		)
		(fp_line
			(start -0.7874 -0.4064)
			(end 0.7874 -0.4064)
			(stroke
				(width 0.1524)
				(type default)
			)
			(layer "F.SilkS")
		)
		(fp_line
			(start 0.7874 0.4064)
			(end -0.7874 0.4064)
			(stroke
				(width 0.1524)
				(type default)
			)
			(layer "F.SilkS")
		)
		(fp_line
			(start -0.7874 0.4064)
			(end -0.7874 -0.4064)
			(stroke
				(width 0.1524)
				(type default)
			)
			(layer "F.SilkS")
		)
		(fp_line
			(start -0.12065 -0.305054)
			(end -0.12065 -0.2794)
			(stroke
				(width 0.1)
				(type default)
			)
			(layer "F.Fab")
		)
		(fp_line
			(start -0.67945 -0.305054)
			(end -0.12065 -0.305054)
			(stroke
				(width 0.1)
				(type default)
			)
			(layer "F.Fab")
		)
		(fp_line
			(start 0.67945 -0.3048)
			(end 0.67945 0.3048)
			(stroke
				(width 0.1)
				(type default)
			)
			(layer "F.Fab")
		)
		(fp_line
			(start 0.12065 -0.3048)
			(end 0.67945 -0.3048)
			(stroke
				(width 0.1)
				(type default)
			)
			(layer "F.Fab")
		)
		(fp_line
			(start 0.12065 -0.2794)
			(end 0.12065 -0.3048)
			(stroke
				(width 0.1)
				(type default)
			)
			(layer "F.Fab")
		)
		(fp_line
			(start -0.12065 -0.2794)
			(end 0.12065 -0.2794)
			(stroke
				(width 0.1)
				(type default)
			)
			(layer "F.Fab")
		)
		(fp_line
			(start 0.120396 0.2794)
			(end -0.12065 0.2794)
			(stroke
				(width 0.1)
				(type default)
			)
			(layer "F.Fab")
		)
		(fp_line
			(start -0.12065 0.2794)
			(end -0.12065 0.3048)
			(stroke
				(width 0.1)
				(type default)
			)
			(layer "F.Fab")
		)
		(fp_line
			(start 0.67945 0.3048)
			(end 0.120396 0.3048)
			(stroke
				(width 0.1)
				(type default)
			)
			(layer "F.Fab")
		)
		(fp_line
			(start 0.120396 0.3048)
			(end 0.120396 0.2794)
			(stroke
				(width 0.1)
				(type default)
			)
			(layer "F.Fab")
		)
		(fp_line
			(start -0.12065 0.3048)
			(end -0.67945 0.3048)
			(stroke
				(width 0.1)
				(type default)
			)
			(layer "F.Fab")
		)
		(fp_line
			(start -0.67945 0.3048)
			(end -0.67945 -0.305054)
			(stroke
				(width 0.1)
				(type default)
			)
			(layer "F.Fab")
		)
		(pad "1" smd circle
			(at -0.40005 0 90)
			(size 0 0)
			(layers "F.Cu" "F.Mask" "F.Paste")
			(net "PVDD18_S5_P0")
		)
		(pad "2" smd circle
			(at 0.40005 0 90)
			(size 0 0)
			(layers "F.Cu" "F.Mask" "F.Paste")
			(net "FM_PLD_CPU1_PRSNT_HDT_N")
		)
	)
	(footprint ""
		(layer "F.Cu")
		(at 296.687748 -344.982038 90)
		(property "Reference" "PR221"
			(at 0 0 90)
			(layer "F.SilkS")
			(hide yes)
			(effects
				(font
					(size 1.27 1.27)
				)
			)
		)
		(property "Value" ""
			(at 0 0 90)
			(layer "F.Fab")
			(effects
				(font
					(size 1.27 1.27)
				)
			)
		)
		(duplicate_pad_numbers_are_jumpers no)
		(fp_line
			(start 0.7874 -0.4064)
			(end 0.7874 0.4064)
			(stroke
				(width 0.1524)
				(type default)
			)
			(layer "F.SilkS")
		)
		(fp_line
			(start -0.7874 -0.4064)
			(end 0.7874 -0.4064)
			(stroke
				(width 0.1524)
				(type default)
			)
			(layer "F.SilkS")
		)
		(fp_line
			(start 0.7874 0.4064)
			(end -0.7874 0.4064)
			(stroke
				(width 0.1524)
				(type default)
			)
			(layer "F.SilkS")
		)
		(fp_line
			(start -0.7874 0.4064)
			(end -0.7874 -0.4064)
			(stroke
				(width 0.1524)
				(type default)
			)
			(layer "F.SilkS")
		)
		(fp_line
			(start -0.12065 -0.305054)
			(end -0.12065 -0.2794)
			(stroke
				(width 0.1)
				(type default)
			)
			(layer "F.Fab")
		)
		(fp_line
			(start -0.67945 -0.305054)
			(end -0.12065 -0.305054)
			(stroke
				(width 0.1)
				(type default)
			)
			(layer "F.Fab")
		)
		(fp_line
			(start 0.67945 -0.3048)
			(end 0.67945 0.3048)
			(stroke
				(width 0.1)
				(type default)
			)
			(layer "F.Fab")
		)
		(fp_line
			(start 0.12065 -0.3048)
			(end 0.67945 -0.3048)
			(stroke
				(width 0.1)
				(type default)
			)
			(layer "F.Fab")
		)
		(fp_line
			(start 0.12065 -0.2794)
			(end 0.12065 -0.3048)
			(stroke
				(width 0.1)
				(type default)
			)
			(layer "F.Fab")
		)
		(fp_line
			(start -0.12065 -0.2794)
			(end 0.12065 -0.2794)
			(stroke
				(width 0.1)
				(type default)
			)
			(layer "F.Fab")
		)
		(fp_line
			(start 0.120396 0.2794)
			(end -0.12065 0.2794)
			(stroke
				(width 0.1)
				(type default)
			)
			(layer "F.Fab")
		)
		(fp_line
			(start -0.12065 0.2794)
			(end -0.12065 0.3048)
			(stroke
				(width 0.1)
				(type default)
			)
			(layer "F.Fab")
		)
		(fp_line
			(start 0.67945 0.3048)
			(end 0.120396 0.3048)
			(stroke
				(width 0.1)
				(type default)
			)
			(layer "F.Fab")
		)
		(fp_line
			(start 0.120396 0.3048)
			(end 0.120396 0.2794)
			(stroke
				(width 0.1)
				(type default)
			)
			(layer "F.Fab")
		)
		(fp_line
			(start -0.12065 0.3048)
			(end -0.67945 0.3048)
			(stroke
				(width 0.1)
				(type default)
			)
			(layer "F.Fab")
		)
		(fp_line
			(start -0.67945 0.3048)
			(end -0.67945 -0.305054)
			(stroke
				(width 0.1)
				(type default)
			)
			(layer "F.Fab")
		)
		(pad "1" smd circle
			(at -0.40005 0 90)
			(size 0 0)
			(layers "F.Cu" "F.Mask" "F.Paste")
			(net "SW_PVDDIO_P0_SW1_RC")
		)
		(pad "2" smd circle
			(at 0.40005 0 90)
			(size 0 0)
			(layers "F.Cu" "F.Mask" "F.Paste")
			(net "GND")
		)
	)
	(footprint ""
		(layer "F.Cu")
		(at 118.718584 -58.868056)
		(property "Reference" "R1735"
			(at 0 0 0)
			(layer "F.SilkS")
			(hide yes)
			(effects
				(font
					(size 1.27 1.27)
				)
			)
		)
		(property "Value" ""
			(at 0 0 0)
			(layer "F.Fab")
			(effects
				(font
					(size 1.27 1.27)
				)
			)
		)
		(duplicate_pad_numbers_are_jumpers no)
		(fp_line
			(start -0.7874 -0.4064)
			(end 0.7874 -0.4064)
			(stroke
				(width 0.1524)
				(type default)
			)
			(layer "F.SilkS")
		)
		(fp_line
			(start -0.7874 0.4064)
			(end -0.7874 -0.4064)
			(stroke
				(width 0.1524)
				(type default)
			)
			(layer "F.SilkS")
		)
		(fp_line
			(start 0.7874 -0.4064)
			(end 0.7874 0.4064)
			(stroke
				(width 0.1524)
				(type default)
			)
			(layer "F.SilkS")
		)
		(fp_line
			(start 0.7874 0.4064)
			(end -0.7874 0.4064)
			(stroke
				(width 0.1524)
				(type default)
			)
			(layer "F.SilkS")
		)
		(fp_line
			(start -0.67945 -0.305054)
			(end -0.12065 -0.305054)
			(stroke
				(width 0.1)
				(type default)
			)
			(layer "F.Fab")
		)
		(fp_line
			(start -0.67945 0.3048)
			(end -0.67945 -0.305054)
			(stroke
				(width 0.1)
				(type default)
			)
			(layer "F.Fab")
		)
		(fp_line
			(start -0.12065 -0.305054)
			(end -0.12065 -0.2794)
			(stroke
				(width 0.1)
				(type default)
			)
			(layer "F.Fab")
		)
		(fp_line
			(start -0.12065 -0.2794)
			(end 0.12065 -0.2794)
			(stroke
				(width 0.1)
				(type default)
			)
			(layer "F.Fab")
		)
		(fp_line
			(start -0.12065 0.2794)
			(end -0.12065 0.3048)
			(stroke
				(width 0.1)
				(type default)
			)
			(layer "F.Fab")
		)
		(fp_line
			(start -0.12065 0.3048)
			(end -0.67945 0.3048)
			(stroke
				(width 0.1)
				(type default)
			)
			(layer "F.Fab")
		)
		(fp_line
			(start 0.120396 0.2794)
			(end -0.12065 0.2794)
			(stroke
				(width 0.1)
				(type default)
			)
			(layer "F.Fab")
		)
		(fp_line
			(start 0.120396 0.3048)
			(end 0.120396 0.2794)
			(stroke
				(width 0.1)
				(type default)
			)
			(layer "F.Fab")
		)
		(fp_line
			(start 0.12065 -0.3048)
			(end 0.67945 -0.3048)
			(stroke
				(width 0.1)
				(type default)
			)
			(layer "F.Fab")
		)
		(fp_line
			(start 0.12065 -0.2794)
			(end 0.12065 -0.3048)
			(stroke
				(width 0.1)
				(type default)
			)
			(layer "F.Fab")
		)
		(fp_line
			(start 0.67945 -0.3048)
			(end 0.67945 0.3048)
			(stroke
				(width 0.1)
				(type default)
			)
			(layer "F.Fab")
		)
		(fp_line
			(start 0.67945 0.3048)
			(end 0.120396 0.3048)
			(stroke
				(width 0.1)
				(type default)
			)
			(layer "F.Fab")
		)
		(pad "1" smd circle
			(at -0.40005 0)
			(size 0 0)
			(layers "F.Cu" "F.Mask" "F.Paste")
			(net "JTAG_SCM_TCK")
		)
		(pad "2" smd circle
			(at 0.40005 0)
			(size 0 0)
			(layers "F.Cu" "F.Mask" "F.Paste")
			(net "GND")
		)
	)
	(footprint ""
		(layer "F.Cu")
		(at 145.161 -120.777)
		(property "Reference" "R8039"
			(at 0 0 0)
			(layer "F.SilkS")
			(hide yes)
			(effects
				(font
					(size 1.27 1.27)
				)
			)
		)
		(property "Value" ""
			(at 0 0 0)
			(layer "F.Fab")
			(effects
				(font
					(size 1.27 1.27)
				)
			)
		)
		(duplicate_pad_numbers_are_jumpers no)
		(fp_line
			(start -0.7874 -0.4064)
			(end 0.7874 -0.4064)
			(stroke
				(width 0.1524)
				(type default)
			)
			(layer "F.SilkS")
		)
		(fp_line
			(start -0.7874 0.4064)
			(end -0.7874 -0.4064)
			(stroke
				(width 0.1524)
				(type default)
			)
			(layer "F.SilkS")
		)
		(fp_line
			(start 0.7874 -0.4064)
			(end 0.7874 0.4064)
			(stroke
				(width 0.1524)
				(type default)
			)
			(layer "F.SilkS")
		)
		(fp_line
			(start 0.7874 0.4064)
			(end -0.7874 0.4064)
			(stroke
				(width 0.1524)
				(type default)
			)
			(layer "F.SilkS")
		)
		(fp_line
			(start -0.67945 -0.305054)
			(end -0.12065 -0.305054)
			(stroke
				(width 0.1)
				(type default)
			)
			(layer "F.Fab")
		)
		(fp_line
			(start -0.67945 0.3048)
			(end -0.67945 -0.305054)
			(stroke
				(width 0.1)
				(type default)
			)
			(layer "F.Fab")
		)
		(fp_line
			(start -0.12065 -0.305054)
			(end -0.12065 -0.2794)
			(stroke
				(width 0.1)
				(type default)
			)
			(layer "F.Fab")
		)
		(fp_line
			(start -0.12065 -0.2794)
			(end 0.12065 -0.2794)
			(stroke
				(width 0.1)
				(type default)
			)
			(layer "F.Fab")
		)
		(fp_line
			(start -0.12065 0.2794)
			(end -0.12065 0.3048)
			(stroke
				(width 0.1)
				(type default)
			)
			(layer "F.Fab")
		)
		(fp_line
			(start -0.12065 0.3048)
			(end -0.67945 0.3048)
			(stroke
				(width 0.1)
				(type default)
			)
			(layer "F.Fab")
		)
		(fp_line
			(start 0.120396 0.2794)
			(end -0.12065 0.2794)
			(stroke
				(width 0.1)
				(type default)
			)
			(layer "F.Fab")
		)
		(fp_line
			(start 0.120396 0.3048)
			(end 0.120396 0.2794)
			(stroke
				(width 0.1)
				(type default)
			)
			(layer "F.Fab")
		)
		(fp_line
			(start 0.12065 -0.3048)
			(end 0.67945 -0.3048)
			(stroke
				(width 0.1)
				(type default)
			)
			(layer "F.Fab")
		)
		(fp_line
			(start 0.12065 -0.2794)
			(end 0.12065 -0.3048)
			(stroke
				(width 0.1)
				(type default)
			)
			(layer "F.Fab")
		)
		(fp_line
			(start 0.67945 -0.3048)
			(end 0.67945 0.3048)
			(stroke
				(width 0.1)
				(type default)
			)
			(layer "F.Fab")
		)
		(fp_line
			(start 0.67945 0.3048)
			(end 0.120396 0.3048)
			(stroke
				(width 0.1)
				(type default)
			)
			(layer "F.Fab")
		)
		(pad "1" smd circle
			(at -0.40005 0)
			(size 0 0)
			(layers "F.Cu" "F.Mask" "F.Paste")
			(net "P3V3_AUX")
		)
		(pad "2" smd circle
			(at 0.40005 0)
			(size 0 0)
			(layers "F.Cu" "F.Mask" "F.Paste")
			(net "PWRGD_CHAF_CPU1")
		)
	)
	(footprint ""
		(layer "F.Cu")
		(at 288.568638 -412.741872 -90)
		(property "Reference" "R4519"
			(at 0 0 270)
			(layer "F.SilkS")
			(hide yes)
			(effects
				(font
					(size 1.27 1.27)
				)
			)
		)
		(property "Value" ""
			(at 0 0 270)
			(layer "F.Fab")
			(effects
				(font
					(size 1.27 1.27)
				)
			)
		)
		(duplicate_pad_numbers_are_jumpers no)
		(fp_line
			(start -0.7874 0.4064)
			(end -0.7874 -0.4064)
			(stroke
				(width 0.1524)
				(type default)
			)
			(layer "F.SilkS")
		)
		(fp_line
			(start 0.7874 0.4064)
			(end -0.7874 0.4064)
			(stroke
				(width 0.1524)
				(type default)
			)
			(layer "F.SilkS")
		)
		(fp_line
			(start -0.7874 -0.4064)
			(end 0.7874 -0.4064)
			(stroke
				(width 0.1524)
				(type default)
			)
			(layer "F.SilkS")
		)
		(fp_line
			(start 0.7874 -0.4064)
			(end 0.7874 0.4064)
			(stroke
				(width 0.1524)
				(type default)
			)
			(layer "F.SilkS")
		)
		(fp_line
			(start -0.67945 0.3048)
			(end -0.67945 -0.305054)
			(stroke
				(width 0.1)
				(type default)
			)
			(layer "F.Fab")
		)
		(fp_line
			(start -0.12065 0.3048)
			(end -0.67945 0.3048)
			(stroke
				(width 0.1)
				(type default)
			)
			(layer "F.Fab")
		)
		(fp_line
			(start 0.120396 0.3048)
			(end 0.120396 0.2794)
			(stroke
				(width 0.1)
				(type default)
			)
			(layer "F.Fab")
		)
		(fp_line
			(start 0.67945 0.3048)
			(end 0.120396 0.3048)
			(stroke
				(width 0.1)
				(type default)
			)
			(layer "F.Fab")
		)
		(fp_line
			(start -0.12065 0.2794)
			(end -0.12065 0.3048)
			(stroke
				(width 0.1)
				(type default)
			)
			(layer "F.Fab")
		)
		(fp_line
			(start 0.120396 0.2794)
			(end -0.12065 0.2794)
			(stroke
				(width 0.1)
				(type default)
			)
			(layer "F.Fab")
		)
		(fp_line
			(start -0.12065 -0.2794)
			(end 0.12065 -0.2794)
			(stroke
				(width 0.1)
				(type default)
			)
			(layer "F.Fab")
		)
		(fp_line
			(start 0.12065 -0.2794)
			(end 0.12065 -0.3048)
			(stroke
				(width 0.1)
				(type default)
			)
			(layer "F.Fab")
		)
		(fp_line
			(start 0.12065 -0.3048)
			(end 0.67945 -0.3048)
			(stroke
				(width 0.1)
				(type default)
			)
			(layer "F.Fab")
		)
		(fp_line
			(start 0.67945 -0.3048)
			(end 0.67945 0.3048)
			(stroke
				(width 0.1)
				(type default)
			)
			(layer "F.Fab")
		)
		(fp_line
			(start -0.67945 -0.305054)
			(end -0.12065 -0.305054)
			(stroke
				(width 0.1)
				(type default)
			)
			(layer "F.Fab")
		)
		(fp_line
			(start -0.12065 -0.305054)
			(end -0.12065 -0.2794)
			(stroke
				(width 0.1)
				(type default)
			)
			(layer "F.Fab")
		)
		(pad "1" smd circle
			(at -0.40005 0 270)
			(size 0 0)
			(layers "F.Cu" "F.Mask" "F.Paste")
			(net "FM_9ZXL045_P0_1_OE_N")
		)
		(pad "2" smd circle
			(at 0.40005 0 270)
			(size 0 0)
			(layers "F.Cu" "F.Mask" "F.Paste")
			(net "GND")
		)
	)
)
